(kicad_pcb
	(version 20260206)
	(generator "pcbnew")
	(generator_version "10.0")
	(general
		(thickness 1.6)
		(legacy_teardrops no)
	)
	(paper "A4")
	(title_block
		(title "v1-chassis-manager — T6M_CM_d_v01_1031_1645.brd")
		(comment 1 "Open CloudServer (Microsoft) / footprints 2113-2121 of 2512")
	)
	(layers
		(0 "F.Cu" signal "TOP")
		(4 "In1.Cu" signal "GND1")
		(6 "In2.Cu" signal "IN1")
		(8 "In3.Cu" signal "VCC1")
		(10 "In4.Cu" signal "VCC2")
		(12 "In5.Cu" signal "GND2")
		(14 "In6.Cu" signal "IN2")
		(16 "In7.Cu" signal "IN3")
		(18 "In8.Cu" signal "GND3")
		(2 "B.Cu" signal "BOTTOM")
		(9 "F.Adhes" user "F.Adhesive")
		(11 "B.Adhes" user "B.Adhesive")
		(13 "F.Paste" user "Package Geometry/Pastemask Top")
		(15 "B.Paste" user "Package Geometry/Pastemask Bottom")
		(5 "F.SilkS" user "Ref Des/Silkscreen Top")
		(7 "B.SilkS" user "Ref Des/Silkscreen Bottom")
		(1 "F.Mask" user "Board Geometry/Soldermask Top")
		(3 "B.Mask" user "Board Geometry/Soldermask Bottom")
		(17 "Dwgs.User" user "User.Drawings")
		(19 "Cmts.User" user "User.Comments")
		(21 "Eco1.User" user "User.Eco1")
		(23 "Eco2.User" user "User.Eco2")
		(25 "Edge.Cuts" user "Board Geometry/Outline")
		(27 "Margin" user)
		(31 "F.CrtYd" user "Package Geometry/Place Bound Top")
		(29 "B.CrtYd" user "Package Geometry/Place Bound Bottom")
		(35 "F.Fab" user "Ref Des/Assembly Top")
		(33 "B.Fab" user "Ref Des/Assembly Bottom")
	)
	(footprint ""
		(layer "B.Cu")
		(at 142.22476 -187.999624 90)
		(property "Reference" "R975"
			(at 4.438396 -1.614678 270)
			(unlocked yes)
			(layer "B.SilkS")
			(effects
				(font
					(size 0.7874 0.5842)
					(thickness 0.1524)
				)
				(justify left mirror)
			)
		)
		(property "Value" ""
			(at 0 0 90)
			(layer "B.Fab")
			(effects
				(font
					(size 1.27 1.27)
				)
				(justify mirror)
			)
		)
		(duplicate_pad_numbers_are_jumpers no)
		(fp_line
			(start 0.7874 -0.4064)
			(end -0.7874 -0.4064)
			(stroke
				(width 0.1524)
				(type default)
			)
			(layer "B.SilkS")
		)
		(fp_line
			(start -0.7874 -0.4064)
			(end -0.7874 0.4064)
			(stroke
				(width 0.1524)
				(type default)
			)
			(layer "B.SilkS")
		)
		(fp_line
			(start 0.7874 0.4064)
			(end 0.7874 -0.4064)
			(stroke
				(width 0.1524)
				(type default)
			)
			(layer "B.SilkS")
		)
		(fp_line
			(start -0.7874 0.4064)
			(end 0.7874 0.4064)
			(stroke
				(width 0.1524)
				(type default)
			)
			(layer "B.SilkS")
		)
		(fp_poly
			(pts
				(xy 0.508 0.2794) (xy 0.508 0.2286) (xy 0.635 0.2286) (xy 0.635 -0.254) (xy 0.5334 -0.254) (xy 0.5334 -0.2794)
				(xy -0.5334 -0.2794) (xy -0.5334 -0.254) (xy -0.635 -0.254) (xy -0.635 0.254) (xy -0.5334 0.254)
				(xy -0.5334 0.2794)
			)
			(stroke
				(width 0)
				(type default)
			)
			(fill no)
			(layer "B.CrtYd")
		)
		(pad "1" smd rect
			(at -0.40005 0 270)
			(size 0.4572 0.508)
			(layers "B.Cu" "B.Mask" "B.Paste")
			(net "UART_T11_NODE4_RXD")
		)
		(pad "2" smd rect
			(at 0.40005 0 270)
			(size 0.4572 0.508)
			(layers "B.Cu" "B.Mask" "B.Paste")
			(net "UART_T11_NODE4_RXD_R")
		)
	)
	(footprint ""
		(layer "B.Cu")
		(at 130.183382 -159.604964 -90)
		(property "Reference" "R1069"
			(at 5.080254 -0.167894 270)
			(unlocked yes)
			(layer "B.SilkS")
			(effects
				(font
					(size 0.7874 0.5842)
					(thickness 0.1524)
				)
				(justify left mirror)
			)
		)
		(property "Value" ""
			(at 0 0 90)
			(layer "B.Fab")
			(effects
				(font
					(size 1.27 1.27)
				)
				(justify mirror)
			)
		)
		(duplicate_pad_numbers_are_jumpers no)
		(fp_line
			(start -0.7874 0.4064)
			(end 0.7874 0.4064)
			(stroke
				(width 0.1524)
				(type default)
			)
			(layer "B.SilkS")
		)
		(fp_line
			(start 0.7874 0.4064)
			(end 0.7874 -0.4064)
			(stroke
				(width 0.1524)
				(type default)
			)
			(layer "B.SilkS")
		)
		(fp_line
			(start -0.7874 -0.4064)
			(end -0.7874 0.4064)
			(stroke
				(width 0.1524)
				(type default)
			)
			(layer "B.SilkS")
		)
		(fp_line
			(start 0.7874 -0.4064)
			(end -0.7874 -0.4064)
			(stroke
				(width 0.1524)
				(type default)
			)
			(layer "B.SilkS")
		)
		(fp_poly
			(pts
				(xy 0.508 0.2794) (xy 0.508 0.2286) (xy 0.635 0.2286) (xy 0.635 -0.254) (xy 0.5334 -0.254) (xy 0.5334 -0.2794)
				(xy -0.5334 -0.2794) (xy -0.5334 -0.254) (xy -0.635 -0.254) (xy -0.635 0.254) (xy -0.5334 0.254)
				(xy -0.5334 0.2794)
			)
			(stroke
				(width 0)
				(type default)
			)
			(fill no)
			(layer "B.CrtYd")
		)
		(pad "1" smd rect
			(at -0.40005 0 90)
			(size 0.4572 0.508)
			(layers "B.Cu" "B.Mask" "B.Paste")
			(net "UART_RI_P6_LS_N")
		)
		(pad "2" smd rect
			(at 0.40005 0 90)
			(size 0.4572 0.508)
			(layers "B.Cu" "B.Mask" "B.Paste")
			(net "UART_RI_P6_N")
		)
	)
	(footprint ""
		(layer "B.Cu")
		(at 76.6953 -87.463884 180)
		(property "Reference" "R144"
			(at -1.2827 1.512062 0)
			(unlocked yes)
			(layer "B.SilkS")
			(effects
				(font
					(size 0.7874 0.5842)
					(thickness 0.1524)
				)
				(justify left mirror)
			)
		)
		(property "Value" ""
			(at 0 0 0)
			(layer "B.Fab")
			(effects
				(font
					(size 1.27 1.27)
				)
				(justify mirror)
			)
		)
		(duplicate_pad_numbers_are_jumpers no)
		(fp_line
			(start 0.7874 0.4064)
			(end 0.7874 -0.4064)
			(stroke
				(width 0.1524)
				(type default)
			)
			(layer "B.SilkS")
		)
		(fp_line
			(start 0.7874 -0.4064)
			(end -0.7874 -0.4064)
			(stroke
				(width 0.1524)
				(type default)
			)
			(layer "B.SilkS")
		)
		(fp_line
			(start -0.7874 0.4064)
			(end 0.7874 0.4064)
			(stroke
				(width 0.1524)
				(type default)
			)
			(layer "B.SilkS")
		)
		(fp_line
			(start -0.7874 -0.4064)
			(end -0.7874 0.4064)
			(stroke
				(width 0.1524)
				(type default)
			)
			(layer "B.SilkS")
		)
		(fp_poly
			(pts
				(xy 0.508 0.2794) (xy 0.508 0.2286) (xy 0.635 0.2286) (xy 0.635 -0.254) (xy 0.5334 -0.254) (xy 0.5334 -0.2794)
				(xy -0.5334 -0.2794) (xy -0.5334 -0.254) (xy -0.635 -0.254) (xy -0.635 0.254) (xy -0.5334 0.254)
				(xy -0.5334 0.2794)
			)
			(stroke
				(width 0)
				(type default)
			)
			(fill no)
			(layer "B.CrtYd")
		)
		(pad "1" smd rect
			(at -0.40005 0)
			(size 0.4572 0.508)
			(layers "B.Cu" "B.Mask" "B.Paste")
			(net "IRQ_LVC3_CPU_NODE1_WAKE_L")
		)
		(pad "2" smd rect
			(at 0.40005 0)
			(size 0.4572 0.508)
			(layers "B.Cu" "B.Mask" "B.Paste")
			(net "P3V3_SUS_NODE1")
		)
	)
	(footprint ""
		(layer "B.Cu")
		(at 90.81262 -171.990512)
		(property "Reference" "R707"
			(at 24.902414 20.163028 0)
			(unlocked yes)
			(layer "B.SilkS")
			(effects
				(font
					(size 0.7874 0.5842)
					(thickness 0.1524)
				)
				(justify left mirror)
			)
		)
		(property "Value" ""
			(at 0 0 0)
			(layer "B.Fab")
			(effects
				(font
					(size 1.27 1.27)
				)
				(justify mirror)
			)
		)
		(duplicate_pad_numbers_are_jumpers no)
		(fp_line
			(start -0.7874 -0.4064)
			(end -0.7874 0.4064)
			(stroke
				(width 0.1524)
				(type default)
			)
			(layer "B.SilkS")
		)
		(fp_line
			(start -0.7874 0.4064)
			(end 0.7874 0.4064)
			(stroke
				(width 0.1524)
				(type default)
			)
			(layer "B.SilkS")
		)
		(fp_line
			(start 0.7874 -0.4064)
			(end -0.7874 -0.4064)
			(stroke
				(width 0.1524)
				(type default)
			)
			(layer "B.SilkS")
		)
		(fp_line
			(start 0.7874 0.4064)
			(end 0.7874 -0.4064)
			(stroke
				(width 0.1524)
				(type default)
			)
			(layer "B.SilkS")
		)
		(fp_poly
			(pts
				(xy 0.508 0.2794) (xy 0.508 0.2286) (xy 0.635 0.2286) (xy 0.635 -0.254) (xy 0.5334 -0.254) (xy 0.5334 -0.2794)
				(xy -0.5334 -0.2794) (xy -0.5334 -0.254) (xy -0.635 -0.254) (xy -0.635 0.254) (xy -0.5334 0.254)
				(xy -0.5334 0.2794)
			)
			(stroke
				(width 0)
				(type default)
			)
			(fill no)
			(layer "B.CrtYd")
		)
		(pad "1" smd rect
			(at -0.40005 0 180)
			(size 0.4572 0.508)
			(layers "B.Cu" "B.Mask" "B.Paste")
			(net "T4_NODE3_EN")
		)
		(pad "2" smd rect
			(at 0.40005 0 180)
			(size 0.4572 0.508)
			(layers "B.Cu" "B.Mask" "B.Paste")
			(net "P5V_NODE1")
		)
	)
	(footprint ""
		(layer "B.Cu")
		(at 167.217852 -104.84739 90)
		(property "Reference" "C372"
			(at 1.423416 6.288278 270)
			(unlocked yes)
			(layer "B.SilkS")
			(effects
				(font
					(size 0.7874 0.5842)
					(thickness 0.1524)
				)
				(justify left mirror)
			)
		)
		(property "Value" ""
			(at 0 0 90)
			(layer "B.Fab")
			(effects
				(font
					(size 1.27 1.27)
				)
				(justify mirror)
			)
		)
		(duplicate_pad_numbers_are_jumpers no)
		(fp_line
			(start 0.7874 -0.4064)
			(end -0.7874 -0.4064)
			(stroke
				(width 0.1524)
				(type default)
			)
			(layer "B.SilkS")
		)
		(fp_line
			(start -0.7874 -0.4064)
			(end -0.7874 0.4064)
			(stroke
				(width 0.1524)
				(type default)
			)
			(layer "B.SilkS")
		)
		(fp_line
			(start 0 0.381)
			(end 0 -0.381)
			(stroke
				(width 0.1524)
				(type default)
			)
			(layer "B.SilkS")
		)
		(fp_line
			(start 0.7874 0.4064)
			(end 0.7874 -0.4064)
			(stroke
				(width 0.1524)
				(type default)
			)
			(layer "B.SilkS")
		)
		(fp_line
			(start -0.7874 0.4064)
			(end 0.7874 0.4064)
			(stroke
				(width 0.1524)
				(type default)
			)
			(layer "B.SilkS")
		)
		(fp_poly
			(pts
				(xy 0.5334 0.254) (xy 0.635 0.254) (xy 0.635 0.2286) (xy 0.635 -0.254) (xy 0.5334 -0.254) (xy 0.5334 -0.2794)
				(xy -0.5334 -0.2794) (xy -0.5334 -0.254) (xy -0.635 -0.254) (xy -0.635 0.254) (xy -0.5334 0.254)
				(xy -0.5334 0.2794) (xy 0.508 0.2794) (xy 0.5334 0.2794)
			)
			(stroke
				(width 0)
				(type default)
			)
			(fill no)
			(layer "B.CrtYd")
		)
		(pad "1" smd rect
			(at -0.40005 0 270)
			(size 0.4572 0.508)
			(layers "B.Cu" "B.Mask" "B.Paste")
			(net "GND")
		)
		(pad "2" smd rect
			(at 0.40005 0 270)
			(size 0.4572 0.508)
			(layers "B.Cu" "B.Mask" "B.Paste")
			(net "P1V05_NODE1")
		)
	)
	(footprint ""
		(layer "B.Cu")
		(at 51.67376 -181.984142 -90)
		(property "Reference" "C603"
			(at 3.610356 10.609072 270)
			(unlocked yes)
			(layer "B.SilkS")
			(effects
				(font
					(size 0.7874 0.5842)
					(thickness 0.1524)
				)
				(justify left mirror)
			)
		)
		(property "Value" ""
			(at 0 0 90)
			(layer "B.Fab")
			(effects
				(font
					(size 1.27 1.27)
				)
				(justify mirror)
			)
		)
		(duplicate_pad_numbers_are_jumpers no)
		(fp_line
			(start -0.7874 0.4064)
			(end 0.7874 0.4064)
			(stroke
				(width 0.1524)
				(type default)
			)
			(layer "B.SilkS")
		)
		(fp_line
			(start 0.7874 0.4064)
			(end 0.7874 -0.4064)
			(stroke
				(width 0.1524)
				(type default)
			)
			(layer "B.SilkS")
		)
		(fp_line
			(start 0 0.381)
			(end 0 -0.381)
			(stroke
				(width 0.1524)
				(type default)
			)
			(layer "B.SilkS")
		)
		(fp_line
			(start -0.7874 -0.4064)
			(end -0.7874 0.4064)
			(stroke
				(width 0.1524)
				(type default)
			)
			(layer "B.SilkS")
		)
		(fp_line
			(start 0.7874 -0.4064)
			(end -0.7874 -0.4064)
			(stroke
				(width 0.1524)
				(type default)
			)
			(layer "B.SilkS")
		)
		(fp_poly
			(pts
				(xy 0.5334 0.254) (xy 0.635 0.254) (xy 0.635 0.2286) (xy 0.635 -0.254) (xy 0.5334 -0.254) (xy 0.5334 -0.2794)
				(xy -0.5334 -0.2794) (xy -0.5334 -0.254) (xy -0.635 -0.254) (xy -0.635 0.254) (xy -0.5334 0.254)
				(xy -0.5334 0.2794) (xy 0.508 0.2794) (xy 0.5334 0.2794)
			)
			(stroke
				(width 0)
				(type default)
			)
			(fill no)
			(layer "B.CrtYd")
		)
		(pad "1" smd rect
			(at -0.40005 0 90)
			(size 0.4572 0.508)
			(layers "B.Cu" "B.Mask" "B.Paste")
			(net "PSU2_DC_OK_R_BUF")
		)
		(pad "2" smd rect
			(at 0.40005 0 90)
			(size 0.4572 0.508)
			(layers "B.Cu" "B.Mask" "B.Paste")
			(net "GND")
		)
	)
	(footprint ""
		(layer "B.Cu")
		(at 53.95976 -185.205624 90)
		(property "Reference" "R910"
			(at 4.15163 0.120904 270)
			(unlocked yes)
			(layer "B.SilkS")
			(effects
				(font
					(size 0.7874 0.5842)
					(thickness 0.1524)
				)
				(justify left mirror)
			)
		)
		(property "Value" ""
			(at 0 0 90)
			(layer "B.Fab")
			(effects
				(font
					(size 1.27 1.27)
				)
				(justify mirror)
			)
		)
		(duplicate_pad_numbers_are_jumpers no)
		(fp_line
			(start 0.7874 -0.4064)
			(end -0.7874 -0.4064)
			(stroke
				(width 0.1524)
				(type default)
			)
			(layer "B.SilkS")
		)
		(fp_line
			(start -0.7874 -0.4064)
			(end -0.7874 0.4064)
			(stroke
				(width 0.1524)
				(type default)
			)
			(layer "B.SilkS")
		)
		(fp_line
			(start 0.7874 0.4064)
			(end 0.7874 -0.4064)
			(stroke
				(width 0.1524)
				(type default)
			)
			(layer "B.SilkS")
		)
		(fp_line
			(start -0.7874 0.4064)
			(end 0.7874 0.4064)
			(stroke
				(width 0.1524)
				(type default)
			)
			(layer "B.SilkS")
		)
		(fp_poly
			(pts
				(xy 0.508 0.2794) (xy 0.508 0.2286) (xy 0.635 0.2286) (xy 0.635 -0.254) (xy 0.5334 -0.254) (xy 0.5334 -0.2794)
				(xy -0.5334 -0.2794) (xy -0.5334 -0.254) (xy -0.635 -0.254) (xy -0.635 0.254) (xy -0.5334 0.254)
				(xy -0.5334 0.2794)
			)
			(stroke
				(width 0)
				(type default)
			)
			(fill no)
			(layer "B.CrtYd")
		)
		(pad "1" smd rect
			(at -0.40005 0 270)
			(size 0.4572 0.508)
			(layers "B.Cu" "B.Mask" "B.Paste")
			(net "UART_T1_NODE1_TXD")
		)
		(pad "2" smd rect
			(at 0.40005 0 270)
			(size 0.4572 0.508)
			(layers "B.Cu" "B.Mask" "B.Paste")
			(net "UART_T1_NODE1_TXD_R")
		)
	)
	(footprint ""
		(layer "B.Cu")
		(at 101.6508 -169.452798 90)
		(property "Reference" "U133"
			(at -1.65227 4.93522 0)
			(unlocked yes)
			(layer "B.SilkS")
			(effects
				(font
					(size 0.7874 0.5842)
					(thickness 0.1524)
				)
				(justify mirror)
			)
		)
		(property "Value" ""
			(at 0 0 90)
			(layer "B.Fab")
			(effects
				(font
					(size 1.27 1.27)
				)
				(justify mirror)
			)
		)
		(duplicate_pad_numbers_are_jumpers no)
		(fp_line
			(start 1.1176 -1.7018)
			(end -1.1176 -1.7018)
			(stroke
				(width 0.1524)
				(type default)
			)
			(layer "B.SilkS")
		)
		(fp_line
			(start 1.1176 -1.7018)
			(end 1.1176 -0.254)
			(stroke
				(width 0.1524)
				(type default)
			)
			(layer "B.SilkS")
		)
		(fp_line
			(start -1.1176 -1.7018)
			(end -1.1176 1.7018)
			(stroke
				(width 0.1524)
				(type default)
			)
			(layer "B.SilkS")
		)
		(fp_line
			(start 1.1176 -0.254)
			(end 0.7112 0)
			(stroke
				(width 0.1524)
				(type default)
			)
			(layer "B.SilkS")
		)
		(fp_line
			(start 0.7112 0)
			(end 1.1176 0.254)
			(stroke
				(width 0.1524)
				(type default)
			)
			(layer "B.SilkS")
		)
		(fp_line
			(start 1.1176 0.254)
			(end 1.1176 1.7018)
			(stroke
				(width 0.1524)
				(type default)
			)
			(layer "B.SilkS")
		)
		(fp_line
			(start -1.1176 1.7018)
			(end 1.1176 1.7018)
			(stroke
				(width 0.1524)
				(type default)
			)
			(layer "B.SilkS")
		)
		(fp_poly
			(pts
				(xy 0.675386 1.8161) (xy 0.446786 2.4003) (xy 0.878586 2.4003)
			)
			(stroke
				(width 0)
				(type default)
			)
			(fill yes)
			(layer "B.SilkS")
		)
		(fp_rect
			(start 1.1176 1.5494)
			(end -1.1176 -1.5494)
			(stroke
				(width 0)
				(type default)
			)
			(fill no)
			(layer "B.CrtYd")
		)
		(fp_line
			(start 1.1176 -1.5494)
			(end -1.1176 -1.5494)
			(stroke
				(width 0.1)
				(type default)
			)
			(layer "B.Fab")
		)
		(fp_line
			(start 1.1176 -1.5494)
			(end 1.1176 -0.254)
			(stroke
				(width 0.1)
				(type default)
			)
			(layer "B.Fab")
		)
		(fp_line
			(start -1.1176 -1.5494)
			(end -1.1176 1.5494)
			(stroke
				(width 0.1)
				(type default)
			)
			(layer "B.Fab")
		)
		(fp_line
			(start 1.1176 -0.254)
			(end 1.1176 0.254)
			(stroke
				(width 0.1)
				(type default)
			)
			(layer "B.Fab")
		)
		(fp_line
			(start 1.1176 0.254)
			(end 1.1176 1.5494)
			(stroke
				(width 0.1)
				(type default)
			)
			(layer "B.Fab")
		)
		(fp_line
			(start -1.1176 1.5494)
			(end 1.1176 1.5494)
			(stroke
				(width 0.1)
				(type default)
			)
			(layer "B.Fab")
		)
		(fp_poly
			(pts
				(xy 0.675386 1.8161) (xy 0.446786 2.4003) (xy 0.878586 2.4003)
			)
			(stroke
				(width 0)
				(type default)
			)
			(fill yes)
			(layer "B.Fab")
		)
		(pad "1" smd rect
			(at 0.649986 0.962406 270)
			(size 0.3302 1.1684)
			(layers "B.Cu" "B.Mask" "B.Paste")
			(net "Net_2267")
		)
		(pad "2" smd rect
			(at 0 0.962406 270)
			(size 0.3302 1.1684)
			(layers "B.Cu" "B.Mask" "B.Paste")
			(net "FAN_PWM_BUF")
		)
		(pad "3" smd rect
			(at -0.649986 0.962406 270)
			(size 0.3302 1.1684)
			(layers "B.Cu" "B.Mask" "B.Paste")
			(net "GND")
		)
		(pad "4" smd rect
			(at -0.649986 -0.962406 270)
			(size 0.3302 1.1684)
			(layers "B.Cu" "B.Mask" "B.Paste")
			(net "FAN_PWM")
		)
		(pad "5" smd rect
			(at 0.649986 -0.962406 270)
			(size 0.3302 1.1684)
			(layers "B.Cu" "B.Mask" "B.Paste")
			(net "P3V3_NODE1")
		)
	)
	(footprint ""
		(layer "B.Cu")
		(at 133.294628 -161.035492)
		(property "Reference" "U140"
			(at 0.30099 3.573526 0)
			(unlocked yes)
			(layer "B.SilkS")
			(effects
				(font
					(size 0.635 0.4064)
					(thickness 0.1524)
				)
				(justify mirror)
			)
		)
		(property "Value" ""
			(at 0 0 0)
			(layer "B.Fab")
			(effects
				(font
					(size 1.27 1.27)
				)
				(justify mirror)
			)
		)
		(duplicate_pad_numbers_are_jumpers no)
		(fp_line
			(start -1.651 -1.905)
			(end -1.651 1.905)
			(stroke
				(width 0.1524)
				(type default)
			)
			(layer "B.SilkS")
		)
		(fp_line
			(start -1.651 1.905)
			(end 1.651 1.905)
			(stroke
				(width 0.1524)
				(type default)
			)
			(layer "B.SilkS")
		)
		(fp_line
			(start 1.651 -1.905)
			(end -1.651 -1.905)
			(stroke
				(width 0.1524)
				(type default)
			)
			(layer "B.SilkS")
		)
		(fp_line
			(start 1.651 1.905)
			(end 1.651 -1.905)
			(stroke
				(width 0.1524)
				(type default)
			)
			(layer "B.SilkS")
		)
		(fp_poly
			(pts
				(xy 1.524 0.7112) (xy 1.524 1.7526) (xy 0.508 1.7526) (xy 0.508 0.6985) (xy -0.508 0.6985) (xy -0.508 1.7526)
				(xy -1.524 1.7526) (xy -1.524 0.6985) (xy -1.524 -0.6985) (xy -0.508 -0.6985) (xy -0.508 -1.7526)
				(xy 0.508 -1.7526) (xy 0.508 -0.6985) (xy 1.524 -0.6985) (xy 1.524 0.6985)
			)
			(stroke
				(width 0)
				(type default)
			)
			(fill no)
			(layer "B.CrtYd")
		)
		(fp_text user "S"
			(at -2.055622 1.362202 180)
			(unlocked yes)
			(layer "B.SilkS")
			(effects
				(font
					(size 0.635 0.4064)
					(thickness 0.1524)
				)
				(justify mirror)
			)
		)
		(fp_text user "D"
			(at -1.275334 -2.379472 180)
			(unlocked yes)
			(layer "B.SilkS")
			(effects
				(font
					(size 0.635 0.4064)
					(thickness 0.1524)
				)
				(justify mirror)
			)
		)
		(fp_text user "G"
			(at 2.132076 1.45288 0)
			(unlocked yes)
			(layer "B.SilkS")
			(effects
				(font
					(size 0.635 0.4064)
					(thickness 0.1524)
				)
				(justify mirror)
			)
		)
		(pad "D" smd rect
			(at 0 -1.1176 180)
			(size 1.016 1.27)
			(layers "B.Cu" "B.Mask" "B.Paste")
			(net "TACKOVER_EN")
		)
		(pad "G" smd rect
			(at 1.016 1.1176 180)
			(size 1.016 1.27)
			(layers "B.Cu" "B.Mask" "B.Paste")
			(net "TACKOVER_EN_N")
		)
		(pad "S" smd rect
			(at -1.016 1.1176 180)
			(size 1.016 1.27)
			(layers "B.Cu" "B.Mask" "B.Paste")
			(net "GND")
		)
	)
)
